(kicad_pcb
	(version 20260206)
	(generator "pcbnew")
	(generator_version "10.0")
	(general
		(thickness 1.6)
		(legacy_teardrops no)
	)
	(paper "A4")
	(title_block
		(title "v1-chassis-manager — T6M_CM_d_v01_1031_1645.brd")
		(comment 1 "Open CloudServer (Microsoft) / footprints 789-794 of 2512")
	)
	(layers
		(0 "F.Cu" signal "TOP")
		(4 "In1.Cu" signal "GND1")
		(6 "In2.Cu" signal "IN1")
		(8 "In3.Cu" signal "VCC1")
		(10 "In4.Cu" signal "VCC2")
		(12 "In5.Cu" signal "GND2")
		(14 "In6.Cu" signal "IN2")
		(16 "In7.Cu" signal "IN3")
		(18 "In8.Cu" signal "GND3")
		(2 "B.Cu" signal "BOTTOM")
		(9 "F.Adhes" user "F.Adhesive")
		(11 "B.Adhes" user "B.Adhesive")
		(13 "F.Paste" user "Package Geometry/Pastemask Top")
		(15 "B.Paste" user "Package Geometry/Pastemask Bottom")
		(5 "F.SilkS" user "Ref Des/Silkscreen Top")
		(7 "B.SilkS" user "Ref Des/Silkscreen Bottom")
		(1 "F.Mask" user "Board Geometry/Soldermask Top")
		(3 "B.Mask" user "Board Geometry/Soldermask Bottom")
		(17 "Dwgs.User" user "User.Drawings")
		(19 "Cmts.User" user "User.Comments")
		(21 "Eco1.User" user "User.Eco1")
		(23 "Eco2.User" user "User.Eco2")
		(25 "Edge.Cuts" user "Board Geometry/Outline")
		(27 "Margin" user)
		(31 "F.CrtYd" user "Package Geometry/Place Bound Top")
		(29 "B.CrtYd" user "Package Geometry/Place Bound Bottom")
		(35 "F.Fab" user "Ref Des/Assembly Top")
		(33 "B.Fab" user "Ref Des/Assembly Bottom")
	)
	(footprint ""
		(layer "F.Cu")
		(at 70.097396 -6.446266)
		(property "Reference" "PU5"
			(at 2.031746 3.663188 90)
			(unlocked yes)
			(layer "F.SilkS")
			(effects
				(font
					(size 0.7874 0.5842)
					(thickness 0.1524)
				)
				(justify left)
			)
		)
		(property "Value" ""
			(at 0 0 0)
			(layer "F.Fab")
			(effects
				(font
					(size 1.27 1.27)
				)
			)
		)
		(duplicate_pad_numbers_are_jumpers no)
		(fp_line
			(start -1.575054 -1.575054)
			(end -1.575054 -1.0414)
			(stroke
				(width 0.1524)
				(type default)
			)
			(layer "F.SilkS")
		)
		(fp_line
			(start -1.575054 1.0922)
			(end -1.575054 1.575054)
			(stroke
				(width 0.1524)
				(type default)
			)
			(layer "F.SilkS")
		)
		(fp_line
			(start -1.575054 1.575054)
			(end -1.0922 1.575054)
			(stroke
				(width 0.1524)
				(type default)
			)
			(layer "F.SilkS")
		)
		(fp_line
			(start -1.0668 -1.575054)
			(end -1.575054 -1.575054)
			(stroke
				(width 0.1524)
				(type default)
			)
			(layer "F.SilkS")
		)
		(fp_line
			(start -0.750062 2.043938)
			(end -0.750062 2.348738)
			(stroke
				(width 0.1524)
				(type default)
			)
			(layer "F.SilkS")
		)
		(fp_line
			(start -0.255778 -2.350262)
			(end -0.255778 -2.045462)
			(stroke
				(width 0.1524)
				(type default)
			)
			(layer "F.SilkS")
		)
		(fp_line
			(start 1.0414 1.575054)
			(end 1.575054 1.575054)
			(stroke
				(width 0.1524)
				(type default)
			)
			(layer "F.SilkS")
		)
		(fp_line
			(start 1.575054 -1.575054)
			(end 1.0414 -1.575054)
			(stroke
				(width 0.1524)
				(type default)
			)
			(layer "F.SilkS")
		)
		(fp_line
			(start 1.575054 -1.0668)
			(end 1.575054 -1.575054)
			(stroke
				(width 0.1524)
				(type default)
			)
			(layer "F.SilkS")
		)
		(fp_line
			(start 1.575054 1.575054)
			(end 1.575054 1.143)
			(stroke
				(width 0.1524)
				(type default)
			)
			(layer "F.SilkS")
		)
		(fp_line
			(start 2.055622 0.25019)
			(end 2.563622 0.25019)
			(stroke
				(width 0.1524)
				(type default)
			)
			(layer "F.SilkS")
		)
		(fp_poly
			(pts
				(xy -1.687576 -1.074166) (xy -2.22504 -2.14884) (xy -2.76225 -1.611376)
			)
			(stroke
				(width 0)
				(type default)
			)
			(fill yes)
			(layer "F.SilkS")
		)
		(fp_poly
			(pts
				(xy -1.575054 1.575054) (xy -0.9398 1.575054) (xy -0.9398 1.9558) (xy 0.9398 1.9558) (xy 0.9398 1.575054)
				(xy 1.575054 1.575054) (xy 1.575054 0.9398) (xy 1.9558 0.9398) (xy 1.9558 -0.9398) (xy 1.575054 -0.9398)
				(xy 1.575054 -1.575054) (xy 0.9398 -1.575054) (xy 0.9398 -1.9558) (xy -0.9398 -1.9558) (xy -0.9398 -1.575054)
				(xy -1.575054 -1.575054) (xy -1.575054 -0.9398) (xy -1.9558 -0.9398) (xy -1.9558 0.9398) (xy -1.575054 0.9398)
			)
			(stroke
				(width 0)
				(type default)
			)
			(fill no)
			(layer "F.CrtYd")
		)
		(fp_line
			(start -1.575054 -1.575054)
			(end 1.575054 -1.575054)
			(stroke
				(width 0.1)
				(type default)
			)
			(layer "F.Fab")
		)
		(fp_line
			(start -1.575054 1.575054)
			(end -1.575054 -1.575054)
			(stroke
				(width 0.1)
				(type default)
			)
			(layer "F.Fab")
		)
		(fp_line
			(start -0.750062 2.043938)
			(end -0.750062 2.348738)
			(stroke
				(width 0.1)
				(type default)
			)
			(layer "F.Fab")
		)
		(fp_line
			(start -0.255778 -2.350262)
			(end -0.255778 -2.045462)
			(stroke
				(width 0.1)
				(type default)
			)
			(layer "F.Fab")
		)
		(fp_line
			(start 1.575054 -1.575054)
			(end 1.575054 1.575054)
			(stroke
				(width 0.1)
				(type default)
			)
			(layer "F.Fab")
		)
		(fp_line
			(start 1.575054 1.575054)
			(end -1.575054 1.575054)
			(stroke
				(width 0.1)
				(type default)
			)
			(layer "F.Fab")
		)
		(fp_line
			(start 2.055622 0.25019)
			(end 2.563622 0.25019)
			(stroke
				(width 0.1)
				(type default)
			)
			(layer "F.Fab")
		)
		(fp_poly
			(pts
				(xy -2.100072 -0.750062) (xy -3.240024 -1.130046) (xy -3.240024 -0.370078)
			)
			(stroke
				(width 0)
				(type default)
			)
			(fill yes)
			(layer "F.Fab")
		)
		(fp_text user "16"
			(at -2.035048 -1.936496 0)
			(unlocked yes)
			(layer "F.SilkS")
			(effects
				(font
					(size 0.635 0.4064)
					(thickness 0.1524)
				)
				(justify left)
			)
		)
		(fp_text user "5"
			(at -1.464056 2.126234 0)
			(unlocked yes)
			(layer "F.SilkS")
			(effects
				(font
					(size 0.635 0.4064)
					(thickness 0.1524)
				)
				(justify left)
			)
		)
		(fp_text user "12"
			(at 1.406652 -1.996948 0)
			(unlocked yes)
			(layer "F.SilkS")
			(effects
				(font
					(size 0.635 0.4064)
					(thickness 0.1524)
				)
				(justify left)
			)
		)
		(fp_text user "9"
			(at 1.902206 0.8128 0)
			(unlocked yes)
			(layer "F.SilkS")
			(effects
				(font
					(size 0.635 0.4064)
					(thickness 0.1524)
				)
				(justify left)
			)
		)
		(fp_text user "16"
			(at -2.457958 -2.225675 0)
			(unlocked yes)
			(layer "F.Fab")
			(effects
				(font
					(size 0.78994 0.579882)
					(thickness 0.000001)
				)
				(justify left)
			)
		)
		(fp_text user "5"
			(at -1.737868 2.295525 0)
			(unlocked yes)
			(layer "F.Fab")
			(effects
				(font
					(size 0.78994 0.579882)
					(thickness 0.000001)
				)
				(justify left)
			)
		)
		(fp_text user "12"
			(at 1.708912 -1.514475 0)
			(unlocked yes)
			(layer "F.Fab")
			(effects
				(font
					(size 0.78994 0.579882)
					(thickness 0.000001)
				)
				(justify left)
			)
		)
		(fp_text user "9"
			(at 1.767586 1.584325 0)
			(unlocked yes)
			(layer "F.Fab")
			(effects
				(font
					(size 0.78994 0.579882)
					(thickness 0.000001)
				)
				(justify left)
			)
		)
		(pad "1" smd rect
			(at -1.474978 -0.750062 90)
			(size 0.254 0.8382)
			(layers "F.Cu" "F.Mask" "F.Paste")
			(net "P3V3_NODE1_FB")
		)
		(pad "2" smd rect
			(at -1.474978 -0.249936 90)
			(size 0.254 0.8382)
			(layers "F.Cu" "F.Mask" "F.Paste")
			(net "P3V3_NODE1_VREG5")
		)
		(pad "3" smd rect
			(at -1.474978 0.249936 90)
			(size 0.254 0.8382)
			(layers "F.Cu" "F.Mask" "F.Paste")
			(net "P3V3_NODE1_SS")
		)
		(pad "4" smd rect
			(at -1.474978 0.750062 90)
			(size 0.254 0.8382)
			(layers "F.Cu" "F.Mask" "F.Paste")
			(net "GND")
		)
		(pad "5" smd rect
			(at -0.750062 1.474978)
			(size 0.254 0.8382)
			(layers "F.Cu" "F.Mask" "F.Paste")
			(net "PWRGD_NODE1_P3V3_PG")
		)
		(pad "6" smd rect
			(at -0.249936 1.474978)
			(size 0.254 0.8382)
			(layers "F.Cu" "F.Mask" "F.Paste")
			(net "FM_CPLD_NODE1_P3V3_S_EN")
		)
		(pad "7" smd rect
			(at 0.249936 1.474978)
			(size 0.254 0.8382)
			(layers "F.Cu" "F.Mask" "F.Paste")
			(net "GND")
		)
		(pad "8" smd rect
			(at 0.750062 1.474978)
			(size 0.254 0.8382)
			(layers "F.Cu" "F.Mask" "F.Paste")
			(net "GND")
		)
		(pad "9" smd rect
			(at 1.474978 0.750062 90)
			(size 0.254 0.8382)
			(layers "F.Cu" "F.Mask" "F.Paste")
			(net "SW_P3V3_NODE1_PH")
		)
		(pad "10" smd rect
			(at 1.474978 0.249936 90)
			(size 0.254 0.8382)
			(layers "F.Cu" "F.Mask" "F.Paste")
			(net "SW_P3V3_NODE1_PH")
		)
		(pad "11" smd rect
			(at 1.474978 -0.249936 90)
			(size 0.254 0.8382)
			(layers "F.Cu" "F.Mask" "F.Paste")
			(net "SW_P3V3_NODE1_PH")
		)
		(pad "12" smd rect
			(at 1.474978 -0.750062 90)
			(size 0.254 0.8382)
			(layers "F.Cu" "F.Mask" "F.Paste")
			(net "SW_P3V3_NODE1_BT")
		)
		(pad "13" smd rect
			(at 0.750062 -1.474978)
			(size 0.254 0.8382)
			(layers "F.Cu" "F.Mask" "F.Paste")
			(net "P12V_AUX")
		)
		(pad "14" smd rect
			(at 0.249936 -1.474978)
			(size 0.254 0.8382)
			(layers "F.Cu" "F.Mask" "F.Paste")
			(net "P12V_AUX")
		)
		(pad "15" smd rect
			(at -0.249936 -1.474978)
			(size 0.254 0.8382)
			(layers "F.Cu" "F.Mask" "F.Paste")
			(net "P5V_STB_NODE1")
		)
		(pad "16" smd rect
			(at -0.750062 -1.474978)
			(size 0.254 0.8382)
			(layers "F.Cu" "F.Mask" "F.Paste")
			(net "P3V3_NODE1")
		)
		(pad "TH" smd rect
			(at 0 0 90)
			(size 1.7018 1.7018)
			(layers "F.Cu" "F.Mask" "F.Paste")
			(net "GND")
		)
		(zone
			(layer "F.Cu")
			(hatch none 0.5)
			(connect_pads
				(clearance 0)
			)
			(min_thickness 0.25)
			(keepout
				(tracks allowed)
				(vias not_allowed)
				(pads allowed)
				(copperpour not_allowed)
				(footprints allowed)
			)
			(placement
				(enabled no)
				(sheetname "")
			)
			(fill
				(thermal_gap 0.5)
				(thermal_bridge_width 0.5)
				(island_removal_mode 0)
			)
			(polygon
				(pts
					(xy 69.106796 -7.436866) (xy 71.087996 -7.436866) (xy 71.087996 -5.455666) (xy 69.106796 -5.455666)
					(xy 69.106796 -5.531866) (xy 71.011796 -5.531866) (xy 71.011796 -7.360666) (xy 69.182996 -7.360666)
					(xy 69.182996 -5.557266) (xy 69.106796 -5.557266)
				)
			)
		)
	)
	(footprint ""
		(layer "F.Cu")
		(at 38.004242 -174.634906)
		(property "Reference" "C771"
			(at -2.461768 1.909318 0)
			(unlocked yes)
			(layer "F.SilkS")
			(effects
				(font
					(size 0.7874 0.5842)
					(thickness 0.1524)
				)
				(justify left)
			)
		)
		(property "Value" ""
			(at 0 0 0)
			(layer "F.Fab")
			(effects
				(font
					(size 1.27 1.27)
				)
			)
		)
		(duplicate_pad_numbers_are_jumpers no)
		(fp_line
			(start -2.2098 -0.9398)
			(end 2.2098 -0.9398)
			(stroke
				(width 0.1524)
				(type default)
			)
			(layer "F.SilkS")
		)
		(fp_line
			(start -2.2098 0.9398)
			(end -2.2098 -0.9398)
			(stroke
				(width 0.1524)
				(type default)
			)
			(layer "F.SilkS")
		)
		(fp_line
			(start 0 -0.9398)
			(end 0 0.9398)
			(stroke
				(width 0.1524)
				(type default)
			)
			(layer "F.SilkS")
		)
		(fp_line
			(start 2.2098 -0.9398)
			(end 2.2098 0.9398)
			(stroke
				(width 0.1524)
				(type default)
			)
			(layer "F.SilkS")
		)
		(fp_line
			(start 2.2098 0.9398)
			(end -2.2098 0.9398)
			(stroke
				(width 0.1524)
				(type default)
			)
			(layer "F.SilkS")
		)
		(fp_poly
			(pts
				(xy -1.6764 0.889) (xy -1.6764 0.7874) (xy -2.0574 0.7874) (xy -2.0574 -0.7874) (xy -1.6764 -0.7874)
				(xy -1.6764 -0.9398) (xy 1.6764 -0.9398) (xy 1.6764 -0.7874) (xy 2.0574 -0.7874) (xy 2.0574 0.7874)
				(xy 1.6764 0.7874) (xy 1.6764 0.9398) (xy -1.6764 0.9398)
			)
			(stroke
				(width 0)
				(type default)
			)
			(fill no)
			(layer "F.CrtYd")
		)
		(fp_line
			(start -1.700022 -0.899922)
			(end 1.700022 -0.899922)
			(stroke
				(width 0.1)
				(type default)
			)
			(layer "F.Fab")
		)
		(fp_line
			(start -1.700022 0.899922)
			(end -1.700022 -0.899922)
			(stroke
				(width 0.1)
				(type default)
			)
			(layer "F.Fab")
		)
		(fp_line
			(start 1.700022 -0.899922)
			(end 1.700022 0.899922)
			(stroke
				(width 0.1)
				(type default)
			)
			(layer "F.Fab")
		)
		(fp_line
			(start 1.700022 0.899922)
			(end -1.700022 0.899922)
			(stroke
				(width 0.1)
				(type default)
			)
			(layer "F.Fab")
		)
		(pad "1" smd rect
			(at 1.4732 0)
			(size 1.1684 1.5748)
			(layers "F.Cu" "F.Mask" "F.Paste")
			(net "P12V_AUX")
		)
		(pad "2" smd rect
			(at -1.4732 0)
			(size 1.1684 1.5748)
			(layers "F.Cu" "F.Mask" "F.Paste")
			(net "GND")
		)
	)
	(footprint ""
		(layer "F.Cu")
		(at 129.45618 -185.180732 -90)
		(property "Reference" "R971"
			(at -4.535678 -0.381 90)
			(unlocked yes)
			(layer "F.SilkS")
			(effects
				(font
					(size 0.7874 0.5842)
					(thickness 0.1524)
				)
				(justify left)
			)
		)
		(property "Value" ""
			(at 0 0 270)
			(layer "F.Fab")
			(effects
				(font
					(size 1.27 1.27)
				)
			)
		)
		(duplicate_pad_numbers_are_jumpers no)
		(fp_line
			(start -0.7874 0.4064)
			(end -0.7874 -0.4064)
			(stroke
				(width 0.1524)
				(type default)
			)
			(layer "F.SilkS")
		)
		(fp_line
			(start 0.7874 0.4064)
			(end -0.7874 0.4064)
			(stroke
				(width 0.1524)
				(type default)
			)
			(layer "F.SilkS")
		)
		(fp_line
			(start -0.7874 -0.4064)
			(end 0.7874 -0.4064)
			(stroke
				(width 0.1524)
				(type default)
			)
			(layer "F.SilkS")
		)
		(fp_line
			(start 0.7874 -0.4064)
			(end 0.7874 0.4064)
			(stroke
				(width 0.1524)
				(type default)
			)
			(layer "F.SilkS")
		)
		(fp_poly
			(pts
				(xy -0.508 0.2794) (xy -0.508 0.2286) (xy -0.635 0.2286) (xy -0.635 -0.254) (xy -0.5334 -0.254)
				(xy -0.5334 -0.2794) (xy 0.5334 -0.2794) (xy 0.5334 -0.254) (xy 0.635 -0.254) (xy 0.635 0.254) (xy 0.5334 0.254)
				(xy 0.5334 0.2794)
			)
			(stroke
				(width 0)
				(type default)
			)
			(fill no)
			(layer "F.CrtYd")
		)
		(pad "1" smd rect
			(at 0.40005 0 270)
			(size 0.4572 0.508)
			(layers "F.Cu" "F.Mask" "F.Paste")
			(net "UART_T9_NODE3_TXD")
		)
		(pad "2" smd rect
			(at -0.40005 0 270)
			(size 0.4572 0.508)
			(layers "F.Cu" "F.Mask" "F.Paste")
			(net "UART_T9_NODE3_TXD_R")
		)
	)
	(footprint ""
		(layer "F.Cu")
		(at 94.25432 -122.323606 -90)
		(property "Reference" "TP172"
			(at 0 0 270)
			(layer "F.SilkS")
			(hide yes)
			(effects
				(font
					(size 1.27 1.27)
				)
			)
		)
		(property "Value" ""
			(at 0 0 270)
			(layer "F.Fab")
			(effects
				(font
					(size 1.27 1.27)
				)
			)
		)
		(duplicate_pad_numbers_are_jumpers no)
		(fp_poly
			(pts
				(arc
					(start 0 0.3302)
					(mid 0 -0.3302)
					(end 0 0.3302)
				)
			)
			(stroke
				(width 0)
				(type default)
			)
			(fill no)
			(layer "B.CrtYd")
		)
		(pad "1" thru_hole circle
			(at 0 0 270)
			(size 0.508 0.508)
			(drill 0.254)
			(layers "*.Cu" "*.Mask")
			(remove_unused_layers no)
			(net "N53313389")
			(clearance 0.127)
			(thermal_gap 0.127)
			(padstack
				(mode front_inner_back)
				(layer "Inner"
					(shape circle)
					(size 0.508 0.508)
					(clearance 0.127)
				)
				(layer "B.Cu"
					(shape circle)
					(size 0.6604 0.6604)
					(clearance 0.0508)
				)
			)
		)
	)
	(footprint ""
		(layer "F.Cu")
		(at 60.81776 -188.126624 90)
		(property "Reference" "C703"
			(at 4.548886 0.234442 90)
			(unlocked yes)
			(layer "F.SilkS")
			(effects
				(font
					(size 0.7874 0.5842)
					(thickness 0.1524)
				)
				(justify left)
			)
		)
		(property "Value" ""
			(at 0 0 90)
			(layer "F.Fab")
			(effects
				(font
					(size 1.27 1.27)
				)
			)
		)
		(duplicate_pad_numbers_are_jumpers no)
		(fp_line
			(start 0.7874 -0.4064)
			(end 0.7874 0.4064)
			(stroke
				(width 0.1524)
				(type default)
			)
			(layer "F.SilkS")
		)
		(fp_line
			(start -0.7874 -0.4064)
			(end 0.7874 -0.4064)
			(stroke
				(width 0.1524)
				(type default)
			)
			(layer "F.SilkS")
		)
		(fp_line
			(start 0 0.381)
			(end 0 -0.381)
			(stroke
				(width 0.1524)
				(type default)
			)
			(layer "F.SilkS")
		)
		(fp_line
			(start 0.7874 0.4064)
			(end -0.7874 0.4064)
			(stroke
				(width 0.1524)
				(type default)
			)
			(layer "F.SilkS")
		)
		(fp_line
			(start -0.7874 0.4064)
			(end -0.7874 -0.4064)
			(stroke
				(width 0.1524)
				(type default)
			)
			(layer "F.SilkS")
		)
		(fp_poly
			(pts
				(xy -0.5334 0.254) (xy -0.635 0.254) (xy -0.635 0.2286) (xy -0.635 -0.254) (xy -0.5334 -0.254) (xy -0.5334 -0.2794)
				(xy 0.5334 -0.2794) (xy 0.5334 -0.254) (xy 0.635 -0.254) (xy 0.635 0.254) (xy 0.5334 0.254) (xy 0.5334 0.2794)
				(xy -0.508 0.2794) (xy -0.5334 0.2794)
			)
			(stroke
				(width 0)
				(type default)
			)
			(fill no)
			(layer "F.CrtYd")
		)
		(pad "1" smd rect
			(at 0.40005 0 90)
			(size 0.4572 0.508)
			(layers "F.Cu" "F.Mask" "F.Paste")
			(net "UART_T2_NODE2_TXD_R")
		)
		(pad "2" smd rect
			(at -0.40005 0 90)
			(size 0.4572 0.508)
			(layers "F.Cu" "F.Mask" "F.Paste")
			(net "GND")
		)
	)
	(footprint ""
		(layer "F.Cu")
		(at 142.83436 -121.451624 -90)
		(property "Reference" "R2"
			(at -2.680716 0.023114 90)
			(unlocked yes)
			(layer "F.SilkS")
			(effects
				(font
					(size 0.7874 0.5842)
					(thickness 0.1524)
				)
			)
		)
		(property "Value" ""
			(at 0 0 270)
			(layer "F.Fab")
			(effects
				(font
					(size 1.27 1.27)
				)
			)
		)
		(duplicate_pad_numbers_are_jumpers no)
		(fp_line
			(start -1.2954 0.5842)
			(end -1.2954 -0.5842)
			(stroke
				(width 0.1524)
				(type default)
			)
			(layer "F.SilkS")
		)
		(fp_line
			(start 1.2954 0.5842)
			(end -1.2954 0.5842)
			(stroke
				(width 0.1524)
				(type default)
			)
			(layer "F.SilkS")
		)
		(fp_line
			(start -1.2954 -0.5842)
			(end 1.2954 -0.5842)
			(stroke
				(width 0.1524)
				(type default)
			)
			(layer "F.SilkS")
		)
		(fp_line
			(start 1.2954 -0.5842)
			(end 1.2954 0.5842)
			(stroke
				(width 0.1524)
				(type default)
			)
			(layer "F.SilkS")
		)
		(fp_poly
			(pts
				(xy 1.143 -0.3556) (xy 1.143 0.3556) (xy 0.8636 0.3556) (xy 0.8636 0.4572) (xy -0.8636 0.4572) (xy -0.8636 0.4318)
				(xy -0.8636 0.3556) (xy -1.143 0.3556) (xy -1.143 -0.3556) (xy -0.8636 -0.3556) (xy -0.8636 -0.4572)
				(xy 0.8636 -0.4572) (xy 0.8636 -0.3556)
			)
			(stroke
				(width 0)
				(type default)
			)
			(fill no)
			(layer "F.CrtYd")
		)
		(pad "1" smd rect
			(at 0.7366 0)
			(size 0.7112 0.8128)
			(layers "F.Cu" "F.Mask" "F.Paste")
			(net "P1V5_NODE1")
		)
		(pad "2" smd rect
			(at -0.7366 0)
			(size 0.7112 0.8128)
			(layers "F.Cu" "F.Mask" "F.Paste")
			(net "P1V5_CLK_NODE1_R")
		)
	)
)
